(kicad_pcb
	(version 20260206)
	(generator "pcbnew")
	(generator_version "10.0")
	(general
		(thickness 1.6)
		(legacy_teardrops no)
	)
	(paper "A4")
	(title_block
		(title "04192023_DAF0TMB3IC0_F0TG_MB_C_brd_V02_OCP.brd")
		(comment 1 "Grand Teton / footprints 3268-3273 of 8354")
	)
	(layers
		(0 "F.Cu" signal "TOP")
		(4 "In1.Cu" signal "GND")
		(6 "In2.Cu" signal "IN1")
		(8 "In3.Cu" signal "GND1")
		(10 "In4.Cu" signal "IN2")
		(12 "In5.Cu" signal "GND2")
		(14 "In6.Cu" signal "IN3")
		(16 "In7.Cu" signal "GND3")
		(18 "In8.Cu" signal "VCC")
		(20 "In9.Cu" signal "VCC1")
		(22 "In10.Cu" signal "GND4")
		(24 "In11.Cu" signal "IN4")
		(26 "In12.Cu" signal "GND5")
		(28 "In13.Cu" signal "IN5")
		(30 "In14.Cu" signal "GND6")
		(32 "In15.Cu" signal "IN6")
		(34 "In16.Cu" signal "GND7")
		(2 "B.Cu" signal "BOTTOM")
		(9 "F.Adhes" user "F.Adhesive")
		(11 "B.Adhes" user "B.Adhesive")
		(13 "F.Paste" user "Package Geometry/Pastemask Top")
		(15 "B.Paste" user "Package Geometry/Pastemask Bottom")
		(5 "F.SilkS" user "Ref Des/Silkscreen Top")
		(7 "B.SilkS" user "Ref Des/Silkscreen Bottom")
		(1 "F.Mask" user "Board Geometry/Soldermask Top")
		(3 "B.Mask" user "Board Geometry/Soldermask Bottom")
		(17 "Dwgs.User" user "User.Drawings")
		(19 "Cmts.User" user "User.Comments")
		(21 "Eco1.User" user "User.Eco1")
		(23 "Eco2.User" user "User.Eco2")
		(25 "Edge.Cuts" user "Board Geometry/Outline")
		(27 "Margin" user)
		(31 "F.CrtYd" user "Package Geometry/Place Bound Top")
		(29 "B.CrtYd" user "Package Geometry/Place Bound Bottom")
		(35 "F.Fab" user "Ref Des/Assembly Top")
		(33 "B.Fab" user "Ref Des/Assembly Bottom")
	)
	(footprint ""
		(layer "F.Cu")
		(at 120.631712 -72.323452)
		(property "Reference" "PC852"
			(at 0 0 0)
			(layer "F.SilkS")
			(hide yes)
			(effects
				(font
					(size 1.27 1.27)
				)
			)
		)
		(property "Value" ""
			(at 0 0 0)
			(layer "F.Fab")
			(effects
				(font
					(size 1.27 1.27)
				)
			)
		)
		(duplicate_pad_numbers_are_jumpers no)
		(fp_line
			(start -0.7874 -0.4064)
			(end 0.7874 -0.4064)
			(stroke
				(width 0.1524)
				(type default)
			)
			(layer "F.SilkS")
		)
		(fp_line
			(start -0.7874 0.4064)
			(end -0.7874 -0.4064)
			(stroke
				(width 0.1524)
				(type default)
			)
			(layer "F.SilkS")
		)
		(fp_line
			(start 0.7874 -0.4064)
			(end 0.7874 0.4064)
			(stroke
				(width 0.1524)
				(type default)
			)
			(layer "F.SilkS")
		)
		(fp_line
			(start 0.7874 0.4064)
			(end -0.7874 0.4064)
			(stroke
				(width 0.1524)
				(type default)
			)
			(layer "F.SilkS")
		)
		(fp_line
			(start -0.67945 -0.305054)
			(end -0.12065 -0.305054)
			(stroke
				(width 0.1)
				(type default)
			)
			(layer "F.Fab")
		)
		(fp_line
			(start -0.67945 0.3048)
			(end -0.67945 -0.305054)
			(stroke
				(width 0.1)
				(type default)
			)
			(layer "F.Fab")
		)
		(fp_line
			(start -0.12065 -0.305054)
			(end -0.12065 -0.2794)
			(stroke
				(width 0.1)
				(type default)
			)
			(layer "F.Fab")
		)
		(fp_line
			(start -0.12065 -0.2794)
			(end 0.12065 -0.2794)
			(stroke
				(width 0.1)
				(type default)
			)
			(layer "F.Fab")
		)
		(fp_line
			(start -0.12065 0.2794)
			(end -0.12065 0.3048)
			(stroke
				(width 0.1)
				(type default)
			)
			(layer "F.Fab")
		)
		(fp_line
			(start -0.12065 0.3048)
			(end -0.67945 0.3048)
			(stroke
				(width 0.1)
				(type default)
			)
			(layer "F.Fab")
		)
		(fp_line
			(start 0.120396 0.2794)
			(end -0.12065 0.2794)
			(stroke
				(width 0.1)
				(type default)
			)
			(layer "F.Fab")
		)
		(fp_line
			(start 0.120396 0.3048)
			(end 0.120396 0.2794)
			(stroke
				(width 0.1)
				(type default)
			)
			(layer "F.Fab")
		)
		(fp_line
			(start 0.12065 -0.3048)
			(end 0.67945 -0.3048)
			(stroke
				(width 0.1)
				(type default)
			)
			(layer "F.Fab")
		)
		(fp_line
			(start 0.12065 -0.2794)
			(end 0.12065 -0.3048)
			(stroke
				(width 0.1)
				(type default)
			)
			(layer "F.Fab")
		)
		(fp_line
			(start 0.67945 -0.3048)
			(end 0.67945 0.3048)
			(stroke
				(width 0.1)
				(type default)
			)
			(layer "F.Fab")
		)
		(fp_line
			(start 0.67945 0.3048)
			(end 0.120396 0.3048)
			(stroke
				(width 0.1)
				(type default)
			)
			(layer "F.Fab")
		)
		(pad "1" smd circle
			(at -0.40005 0)
			(size 0 0)
			(layers "F.Cu" "F.Mask" "F.Paste")
			(net "P1V2_AUX_FB")
		)
		(pad "2" smd circle
			(at 0.40005 0)
			(size 0 0)
			(layers "F.Cu" "F.Mask" "F.Paste")
			(net "P1V2_AUX")
		)
	)
	(footprint ""
		(layer "F.Cu")
		(at 24.640794 -394.410184)
		(property "Reference" "PR6628"
			(at 0 0 0)
			(layer "F.SilkS")
			(hide yes)
			(effects
				(font
					(size 1.27 1.27)
				)
			)
		)
		(property "Value" ""
			(at 0 0 0)
			(layer "F.Fab")
			(effects
				(font
					(size 1.27 1.27)
				)
			)
		)
		(duplicate_pad_numbers_are_jumpers no)
		(fp_line
			(start -0.7874 -0.4064)
			(end 0.7874 -0.4064)
			(stroke
				(width 0.1524)
				(type default)
			)
			(layer "F.SilkS")
		)
		(fp_line
			(start -0.7874 0.4064)
			(end -0.7874 -0.4064)
			(stroke
				(width 0.1524)
				(type default)
			)
			(layer "F.SilkS")
		)
		(fp_line
			(start 0.7874 -0.4064)
			(end 0.7874 0.4064)
			(stroke
				(width 0.1524)
				(type default)
			)
			(layer "F.SilkS")
		)
		(fp_line
			(start 0.7874 0.4064)
			(end -0.7874 0.4064)
			(stroke
				(width 0.1524)
				(type default)
			)
			(layer "F.SilkS")
		)
		(fp_line
			(start -0.67945 -0.305054)
			(end -0.12065 -0.305054)
			(stroke
				(width 0.1)
				(type default)
			)
			(layer "F.Fab")
		)
		(fp_line
			(start -0.67945 0.3048)
			(end -0.67945 -0.305054)
			(stroke
				(width 0.1)
				(type default)
			)
			(layer "F.Fab")
		)
		(fp_line
			(start -0.12065 -0.305054)
			(end -0.12065 -0.2794)
			(stroke
				(width 0.1)
				(type default)
			)
			(layer "F.Fab")
		)
		(fp_line
			(start -0.12065 -0.2794)
			(end 0.12065 -0.2794)
			(stroke
				(width 0.1)
				(type default)
			)
			(layer "F.Fab")
		)
		(fp_line
			(start -0.12065 0.2794)
			(end -0.12065 0.3048)
			(stroke
				(width 0.1)
				(type default)
			)
			(layer "F.Fab")
		)
		(fp_line
			(start -0.12065 0.3048)
			(end -0.67945 0.3048)
			(stroke
				(width 0.1)
				(type default)
			)
			(layer "F.Fab")
		)
		(fp_line
			(start 0.120396 0.2794)
			(end -0.12065 0.2794)
			(stroke
				(width 0.1)
				(type default)
			)
			(layer "F.Fab")
		)
		(fp_line
			(start 0.120396 0.3048)
			(end 0.120396 0.2794)
			(stroke
				(width 0.1)
				(type default)
			)
			(layer "F.Fab")
		)
		(fp_line
			(start 0.12065 -0.3048)
			(end 0.67945 -0.3048)
			(stroke
				(width 0.1)
				(type default)
			)
			(layer "F.Fab")
		)
		(fp_line
			(start 0.12065 -0.2794)
			(end 0.12065 -0.3048)
			(stroke
				(width 0.1)
				(type default)
			)
			(layer "F.Fab")
		)
		(fp_line
			(start 0.67945 -0.3048)
			(end 0.67945 0.3048)
			(stroke
				(width 0.1)
				(type default)
			)
			(layer "F.Fab")
		)
		(fp_line
			(start 0.67945 0.3048)
			(end 0.120396 0.3048)
			(stroke
				(width 0.1)
				(type default)
			)
			(layer "F.Fab")
		)
		(pad "1" smd circle
			(at -0.40005 0)
			(size 0 0)
			(layers "F.Cu" "F.Mask" "F.Paste")
			(net "P0V9_RETIMER_CPU1_LSET2")
		)
		(pad "2" smd circle
			(at 0.40005 0)
			(size 0 0)
			(layers "F.Cu" "F.Mask" "F.Paste")
			(net "GND")
		)
	)
	(footprint ""
		(layer "F.Cu")
		(at 56.50992 -30.648148)
		(property "Reference" "R3236"
			(at 0 0 0)
			(layer "F.SilkS")
			(hide yes)
			(effects
				(font
					(size 1.27 1.27)
				)
			)
		)
		(property "Value" ""
			(at 0 0 0)
			(layer "F.Fab")
			(effects
				(font
					(size 1.27 1.27)
				)
			)
		)
		(duplicate_pad_numbers_are_jumpers no)
		(fp_line
			(start -0.7874 -0.4064)
			(end 0.7874 -0.4064)
			(stroke
				(width 0.1524)
				(type default)
			)
			(layer "F.SilkS")
		)
		(fp_line
			(start -0.7874 0.4064)
			(end -0.7874 -0.4064)
			(stroke
				(width 0.1524)
				(type default)
			)
			(layer "F.SilkS")
		)
		(fp_line
			(start 0.7874 -0.4064)
			(end 0.7874 0.4064)
			(stroke
				(width 0.1524)
				(type default)
			)
			(layer "F.SilkS")
		)
		(fp_line
			(start 0.7874 0.4064)
			(end -0.7874 0.4064)
			(stroke
				(width 0.1524)
				(type default)
			)
			(layer "F.SilkS")
		)
		(fp_line
			(start -0.67945 -0.305054)
			(end -0.12065 -0.305054)
			(stroke
				(width 0.1)
				(type default)
			)
			(layer "F.Fab")
		)
		(fp_line
			(start -0.67945 0.3048)
			(end -0.67945 -0.305054)
			(stroke
				(width 0.1)
				(type default)
			)
			(layer "F.Fab")
		)
		(fp_line
			(start -0.12065 -0.305054)
			(end -0.12065 -0.2794)
			(stroke
				(width 0.1)
				(type default)
			)
			(layer "F.Fab")
		)
		(fp_line
			(start -0.12065 -0.2794)
			(end 0.12065 -0.2794)
			(stroke
				(width 0.1)
				(type default)
			)
			(layer "F.Fab")
		)
		(fp_line
			(start -0.12065 0.2794)
			(end -0.12065 0.3048)
			(stroke
				(width 0.1)
				(type default)
			)
			(layer "F.Fab")
		)
		(fp_line
			(start -0.12065 0.3048)
			(end -0.67945 0.3048)
			(stroke
				(width 0.1)
				(type default)
			)
			(layer "F.Fab")
		)
		(fp_line
			(start 0.120396 0.2794)
			(end -0.12065 0.2794)
			(stroke
				(width 0.1)
				(type default)
			)
			(layer "F.Fab")
		)
		(fp_line
			(start 0.120396 0.3048)
			(end 0.120396 0.2794)
			(stroke
				(width 0.1)
				(type default)
			)
			(layer "F.Fab")
		)
		(fp_line
			(start 0.12065 -0.3048)
			(end 0.67945 -0.3048)
			(stroke
				(width 0.1)
				(type default)
			)
			(layer "F.Fab")
		)
		(fp_line
			(start 0.12065 -0.2794)
			(end 0.12065 -0.3048)
			(stroke
				(width 0.1)
				(type default)
			)
			(layer "F.Fab")
		)
		(fp_line
			(start 0.67945 -0.3048)
			(end 0.67945 0.3048)
			(stroke
				(width 0.1)
				(type default)
			)
			(layer "F.Fab")
		)
		(fp_line
			(start 0.67945 0.3048)
			(end 0.120396 0.3048)
			(stroke
				(width 0.1)
				(type default)
			)
			(layer "F.Fab")
		)
		(pad "1" smd circle
			(at -0.40005 0)
			(size 0 0)
			(layers "F.Cu" "F.Mask" "F.Paste")
			(net "RST_HP_OCP_V3_2_R_N")
		)
		(pad "2" smd circle
			(at 0.40005 0)
			(size 0 0)
			(layers "F.Cu" "F.Mask" "F.Paste")
			(net "RST_SMB_OCP_V3_2_N")
		)
	)
	(footprint ""
		(layer "F.Cu")
		(at 93.29801 -54.701694)
		(property "Reference" "PR3782"
			(at 0 0 0)
			(layer "F.SilkS")
			(hide yes)
			(effects
				(font
					(size 1.27 1.27)
				)
			)
		)
		(property "Value" ""
			(at 0 0 0)
			(layer "F.Fab")
			(effects
				(font
					(size 1.27 1.27)
				)
			)
		)
		(duplicate_pad_numbers_are_jumpers no)
		(fp_line
			(start -0.7874 -0.4064)
			(end 0.7874 -0.4064)
			(stroke
				(width 0.1524)
				(type default)
			)
			(layer "F.SilkS")
		)
		(fp_line
			(start -0.7874 0.4064)
			(end -0.7874 -0.4064)
			(stroke
				(width 0.1524)
				(type default)
			)
			(layer "F.SilkS")
		)
		(fp_line
			(start 0.7874 -0.4064)
			(end 0.7874 0.4064)
			(stroke
				(width 0.1524)
				(type default)
			)
			(layer "F.SilkS")
		)
		(fp_line
			(start 0.7874 0.4064)
			(end -0.7874 0.4064)
			(stroke
				(width 0.1524)
				(type default)
			)
			(layer "F.SilkS")
		)
		(fp_line
			(start -0.67945 -0.305054)
			(end -0.12065 -0.305054)
			(stroke
				(width 0.1)
				(type default)
			)
			(layer "F.Fab")
		)
		(fp_line
			(start -0.67945 0.3048)
			(end -0.67945 -0.305054)
			(stroke
				(width 0.1)
				(type default)
			)
			(layer "F.Fab")
		)
		(fp_line
			(start -0.12065 -0.305054)
			(end -0.12065 -0.2794)
			(stroke
				(width 0.1)
				(type default)
			)
			(layer "F.Fab")
		)
		(fp_line
			(start -0.12065 -0.2794)
			(end 0.12065 -0.2794)
			(stroke
				(width 0.1)
				(type default)
			)
			(layer "F.Fab")
		)
		(fp_line
			(start -0.12065 0.2794)
			(end -0.12065 0.3048)
			(stroke
				(width 0.1)
				(type default)
			)
			(layer "F.Fab")
		)
		(fp_line
			(start -0.12065 0.3048)
			(end -0.67945 0.3048)
			(stroke
				(width 0.1)
				(type default)
			)
			(layer "F.Fab")
		)
		(fp_line
			(start 0.120396 0.2794)
			(end -0.12065 0.2794)
			(stroke
				(width 0.1)
				(type default)
			)
			(layer "F.Fab")
		)
		(fp_line
			(start 0.120396 0.3048)
			(end 0.120396 0.2794)
			(stroke
				(width 0.1)
				(type default)
			)
			(layer "F.Fab")
		)
		(fp_line
			(start 0.12065 -0.3048)
			(end 0.67945 -0.3048)
			(stroke
				(width 0.1)
				(type default)
			)
			(layer "F.Fab")
		)
		(fp_line
			(start 0.12065 -0.2794)
			(end 0.12065 -0.3048)
			(stroke
				(width 0.1)
				(type default)
			)
			(layer "F.Fab")
		)
		(fp_line
			(start 0.67945 -0.3048)
			(end 0.67945 0.3048)
			(stroke
				(width 0.1)
				(type default)
			)
			(layer "F.Fab")
		)
		(fp_line
			(start 0.67945 0.3048)
			(end 0.120396 0.3048)
			(stroke
				(width 0.1)
				(type default)
			)
			(layer "F.Fab")
		)
		(pad "1" smd circle
			(at -0.40005 0)
			(size 0 0)
			(layers "F.Cu" "F.Mask" "F.Paste")
			(net "P3V3_AUX")
		)
		(pad "2" smd circle
			(at 0.40005 0)
			(size 0 0)
			(layers "F.Cu" "F.Mask" "F.Paste")
			(net "P3V3_OCP_VCC_2")
		)
	)
	(footprint ""
		(layer "F.Cu")
		(at 164.544756 -42.177462)
		(property "Reference" "R155"
			(at 0 0 0)
			(layer "F.SilkS")
			(hide yes)
			(effects
				(font
					(size 1.27 1.27)
				)
			)
		)
		(property "Value" ""
			(at 0 0 0)
			(layer "F.Fab")
			(effects
				(font
					(size 1.27 1.27)
				)
			)
		)
		(duplicate_pad_numbers_are_jumpers no)
		(fp_line
			(start -0.7874 -0.4064)
			(end 0.7874 -0.4064)
			(stroke
				(width 0.1524)
				(type default)
			)
			(layer "F.SilkS")
		)
		(fp_line
			(start -0.7874 0.4064)
			(end -0.7874 -0.4064)
			(stroke
				(width 0.1524)
				(type default)
			)
			(layer "F.SilkS")
		)
		(fp_line
			(start 0.7874 -0.4064)
			(end 0.7874 0.4064)
			(stroke
				(width 0.1524)
				(type default)
			)
			(layer "F.SilkS")
		)
		(fp_line
			(start 0.7874 0.4064)
			(end -0.7874 0.4064)
			(stroke
				(width 0.1524)
				(type default)
			)
			(layer "F.SilkS")
		)
		(fp_line
			(start -0.67945 -0.305054)
			(end -0.12065 -0.305054)
			(stroke
				(width 0.1)
				(type default)
			)
			(layer "F.Fab")
		)
		(fp_line
			(start -0.67945 0.3048)
			(end -0.67945 -0.305054)
			(stroke
				(width 0.1)
				(type default)
			)
			(layer "F.Fab")
		)
		(fp_line
			(start -0.12065 -0.305054)
			(end -0.12065 -0.2794)
			(stroke
				(width 0.1)
				(type default)
			)
			(layer "F.Fab")
		)
		(fp_line
			(start -0.12065 -0.2794)
			(end 0.12065 -0.2794)
			(stroke
				(width 0.1)
				(type default)
			)
			(layer "F.Fab")
		)
		(fp_line
			(start -0.12065 0.2794)
			(end -0.12065 0.3048)
			(stroke
				(width 0.1)
				(type default)
			)
			(layer "F.Fab")
		)
		(fp_line
			(start -0.12065 0.3048)
			(end -0.67945 0.3048)
			(stroke
				(width 0.1)
				(type default)
			)
			(layer "F.Fab")
		)
		(fp_line
			(start 0.120396 0.2794)
			(end -0.12065 0.2794)
			(stroke
				(width 0.1)
				(type default)
			)
			(layer "F.Fab")
		)
		(fp_line
			(start 0.120396 0.3048)
			(end 0.120396 0.2794)
			(stroke
				(width 0.1)
				(type default)
			)
			(layer "F.Fab")
		)
		(fp_line
			(start 0.12065 -0.3048)
			(end 0.67945 -0.3048)
			(stroke
				(width 0.1)
				(type default)
			)
			(layer "F.Fab")
		)
		(fp_line
			(start 0.12065 -0.2794)
			(end 0.12065 -0.3048)
			(stroke
				(width 0.1)
				(type default)
			)
			(layer "F.Fab")
		)
		(fp_line
			(start 0.67945 -0.3048)
			(end 0.67945 0.3048)
			(stroke
				(width 0.1)
				(type default)
			)
			(layer "F.Fab")
		)
		(fp_line
			(start 0.67945 0.3048)
			(end 0.120396 0.3048)
			(stroke
				(width 0.1)
				(type default)
			)
			(layer "F.Fab")
		)
		(pad "1" smd circle
			(at -0.40005 0)
			(size 0 0)
			(layers "F.Cu" "F.Mask" "F.Paste")
			(net "P3V3_AUX")
		)
		(pad "2" smd circle
			(at 0.40005 0)
			(size 0 0)
			(layers "F.Cu" "F.Mask" "F.Paste")
			(net "M2_SSD0_CLKREQ_EN_N_BUF")
		)
	)
	(footprint ""
		(layer "F.Cu")
		(at 171.196 -108.168948 180)
		(property "Reference" "R50"
			(at 0 0 180)
			(layer "F.SilkS")
			(hide yes)
			(effects
				(font
					(size 1.27 1.27)
				)
			)
		)
		(property "Value" ""
			(at 0 0 180)
			(layer "F.Fab")
			(effects
				(font
					(size 1.27 1.27)
				)
			)
		)
		(duplicate_pad_numbers_are_jumpers no)
		(fp_line
			(start 0.7874 0.4064)
			(end -0.7874 0.4064)
			(stroke
				(width 0.1524)
				(type default)
			)
			(layer "F.SilkS")
		)
		(fp_line
			(start 0.7874 -0.4064)
			(end 0.7874 0.4064)
			(stroke
				(width 0.1524)
				(type default)
			)
			(layer "F.SilkS")
		)
		(fp_line
			(start -0.7874 0.4064)
			(end -0.7874 -0.4064)
			(stroke
				(width 0.1524)
				(type default)
			)
			(layer "F.SilkS")
		)
		(fp_line
			(start -0.7874 -0.4064)
			(end 0.7874 -0.4064)
			(stroke
				(width 0.1524)
				(type default)
			)
			(layer "F.SilkS")
		)
		(fp_line
			(start 0.67945 0.3048)
			(end 0.120396 0.3048)
			(stroke
				(width 0.1)
				(type default)
			)
			(layer "F.Fab")
		)
		(fp_line
			(start 0.67945 -0.3048)
			(end 0.67945 0.3048)
			(stroke
				(width 0.1)
				(type default)
			)
			(layer "F.Fab")
		)
		(fp_line
			(start 0.12065 -0.2794)
			(end 0.12065 -0.3048)
			(stroke
				(width 0.1)
				(type default)
			)
			(layer "F.Fab")
		)
		(fp_line
			(start 0.12065 -0.3048)
			(end 0.67945 -0.3048)
			(stroke
				(width 0.1)
				(type default)
			)
			(layer "F.Fab")
		)
		(fp_line
			(start 0.120396 0.3048)
			(end 0.120396 0.2794)
			(stroke
				(width 0.1)
				(type default)
			)
			(layer "F.Fab")
		)
		(fp_line
			(start 0.120396 0.2794)
			(end -0.12065 0.2794)
			(stroke
				(width 0.1)
				(type default)
			)
			(layer "F.Fab")
		)
		(fp_line
			(start -0.12065 0.3048)
			(end -0.67945 0.3048)
			(stroke
				(width 0.1)
				(type default)
			)
			(layer "F.Fab")
		)
		(fp_line
			(start -0.12065 0.2794)
			(end -0.12065 0.3048)
			(stroke
				(width 0.1)
				(type default)
			)
			(layer "F.Fab")
		)
		(fp_line
			(start -0.12065 -0.2794)
			(end 0.12065 -0.2794)
			(stroke
				(width 0.1)
				(type default)
			)
			(layer "F.Fab")
		)
		(fp_line
			(start -0.12065 -0.305054)
			(end -0.12065 -0.2794)
			(stroke
				(width 0.1)
				(type default)
			)
			(layer "F.Fab")
		)
		(fp_line
			(start -0.67945 0.3048)
			(end -0.67945 -0.305054)
			(stroke
				(width 0.1)
				(type default)
			)
			(layer "F.Fab")
		)
		(fp_line
			(start -0.67945 -0.305054)
			(end -0.12065 -0.305054)
			(stroke
				(width 0.1)
				(type default)
			)
			(layer "F.Fab")
		)
		(pad "1" smd circle
			(at -0.40005 0 180)
			(size 0 0)
			(layers "F.Cu" "F.Mask" "F.Paste")
			(net "SCM_JTAG_MUX_R_S1")
		)
		(pad "2" smd circle
			(at 0.40005 0 180)
			(size 0 0)
			(layers "F.Cu" "F.Mask" "F.Paste")
			(net "SCM_JTAG_MUX_S1")
		)
	)
)
